(kicad_pcb
	(version 20260206)
	(generator "pcbnew")
	(generator_version "10.0")
	(general
		(thickness 1.6)
		(legacy_teardrops no)
	)
	(paper "A4")
	(title_block
		(title "Wiwynn_Tioga_Pass_MB.brd")
		(comment 1 "Tioga Pass / footprints 782-789 of 4770")
	)
	(layers
		(0 "F.Cu" signal "TOP")
		(4 "In1.Cu" signal "L2GND")
		(6 "In2.Cu" signal "L3")
		(8 "In3.Cu" signal "L4GND")
		(10 "In4.Cu" signal "L5")
		(12 "In5.Cu" signal "L6GND")
		(14 "In6.Cu" signal "L7VCC")
		(16 "In7.Cu" signal "L8VCC")
		(18 "In8.Cu" signal "L9GND")
		(20 "In9.Cu" signal "L10")
		(22 "In10.Cu" signal "L11GND")
		(24 "In11.Cu" signal "L12")
		(26 "In12.Cu" signal "L13GND")
		(2 "B.Cu" signal "BOTTOM")
		(9 "F.Adhes" user "F.Adhesive")
		(11 "B.Adhes" user "B.Adhesive")
		(13 "F.Paste" user "Package Geometry/Pastemask Top")
		(15 "B.Paste" user "Package Geometry/Pastemask Bottom")
		(5 "F.SilkS" user "Ref Des/Silkscreen Top")
		(7 "B.SilkS" user "Ref Des/Silkscreen Bottom")
		(1 "F.Mask" user "Board Geometry/Soldermask Top")
		(3 "B.Mask" user "Board Geometry/Soldermask Bottom")
		(17 "Dwgs.User" user "User.Drawings")
		(19 "Cmts.User" user "User.Comments")
		(21 "Eco1.User" user "User.Eco1")
		(23 "Eco2.User" user "User.Eco2")
		(25 "Edge.Cuts" user "Board Geometry/Outline")
		(27 "Margin" user)
		(31 "F.CrtYd" user "Package Geometry/Place Bound Top")
		(29 "B.CrtYd" user "Package Geometry/Place Bound Bottom")
		(35 "F.Fab" user "Ref Des/Assembly Top")
		(33 "B.Fab" user "Ref Des/Assembly Bottom")
	)
	(footprint ""
		(layer "F.Cu")
		(at 352.759518 -143.483076 -90)
		(property "Reference" "C7A22"
			(at 0 0 270)
			(layer "F.SilkS")
			(hide yes)
			(effects
				(font
					(size 1.27 1.27)
				)
			)
		)
		(property "Value" ""
			(at 0 0 270)
			(layer "F.Fab")
			(effects
				(font
					(size 1.27 1.27)
				)
			)
		)
		(duplicate_pad_numbers_are_jumpers no)
		(fp_poly
			(pts
				(xy 0.3048 -0.1016) (xy 0.3048 0.9906) (xy -0.3048 0.9906) (xy -0.3048 -0.1016)
			)
			(stroke
				(width 0)
				(type default)
			)
			(fill no)
			(layer "F.CrtYd")
		)
		(fp_line
			(start -0.3048 0.9906)
			(end 0.3048 0.9906)
			(stroke
				(width 0.1)
				(type default)
			)
			(layer "F.Fab")
		)
		(fp_line
			(start 0.3048 0.9906)
			(end 0.3048 -0.1016)
			(stroke
				(width 0.1)
				(type default)
			)
			(layer "F.Fab")
		)
		(fp_line
			(start -0.3048 -0.1016)
			(end -0.3048 0.9906)
			(stroke
				(width 0.1)
				(type default)
			)
			(layer "F.Fab")
		)
		(fp_line
			(start 0.3048 -0.1016)
			(end -0.3048 -0.1016)
			(stroke
				(width 0.1)
				(type default)
			)
			(layer "F.Fab")
		)
		(pad "1" smd rect
			(at 0 0 270)
			(size 0.508 0.508)
			(layers "F.Cu" "F.Mask" "F.Paste")
			(net "VR_PVDDQ_DEF_PH2_BOOT")
		)
		(pad "2" smd rect
			(at 0 0.889 270)
			(size 0.508 0.508)
			(layers "F.Cu" "F.Mask" "F.Paste")
			(net "VR_PVDDQ_DEF_PH2_PHASE")
		)
		(zone
			(layer "F.Cu")
			(hatch none 0.5)
			(connect_pads
				(clearance 0)
			)
			(min_thickness 0.25)
			(keepout
				(tracks not_allowed)
				(vias allowed)
				(pads allowed)
				(copperpour not_allowed)
				(footprints allowed)
			)
			(placement
				(enabled no)
				(sheetname "")
			)
			(fill
				(thermal_gap 0.5)
				(thermal_bridge_width 0.5)
				(island_removal_mode 0)
			)
			(polygon
				(pts
					(xy 352.124518 -143.737076) (xy 352.124518 -143.229076) (xy 352.505518 -143.229076) (xy 352.505518 -143.737076)
				)
			)
		)
		(zone
			(layer "F.Cu")
			(hatch none 0.5)
			(connect_pads
				(clearance 0)
			)
			(min_thickness 0.25)
			(keepout
				(tracks allowed)
				(vias not_allowed)
				(pads allowed)
				(copperpour not_allowed)
				(footprints allowed)
			)
			(placement
				(enabled no)
				(sheetname "")
			)
			(fill
				(thermal_gap 0.5)
				(thermal_bridge_width 0.5)
				(island_removal_mode 0)
			)
			(polygon
				(pts
					(xy 352.505518 -143.737076) (xy 352.505518 -143.229076) (xy 352.124518 -143.229076) (xy 352.124518 -143.737076)
				)
			)
		)
	)
	(footprint ""
		(layer "F.Cu")
		(at 419.5445 -113.03 90)
		(property "Reference" "R9W17"
			(at -0.8382 -0.67818 90)
			(unlocked yes)
			(layer "F.SilkS")
			(effects
				(font
					(size 0.4064 0.254)
					(thickness 0.1524)
				)
				(justify left)
			)
		)
		(property "Value" ""
			(at 0 0 90)
			(layer "F.Fab")
			(effects
				(font
					(size 1.27 1.27)
				)
			)
		)
		(duplicate_pad_numbers_are_jumpers no)
		(fp_poly
			(pts
				(xy -0.2794 -0.1016) (xy 0.2794 -0.1016) (xy 0.2794 0.9906) (xy -0.2794 0.9906)
			)
			(stroke
				(width 0)
				(type default)
			)
			(fill no)
			(layer "F.CrtYd")
		)
		(fp_line
			(start 0.2794 -0.1016)
			(end -0.2794 -0.1016)
			(stroke
				(width 0.1)
				(type default)
			)
			(layer "F.Fab")
		)
		(fp_line
			(start -0.2794 -0.1016)
			(end -0.2794 0.9906)
			(stroke
				(width 0.1)
				(type default)
			)
			(layer "F.Fab")
		)
		(fp_line
			(start 0.2794 0.9906)
			(end 0.2794 -0.1016)
			(stroke
				(width 0.1)
				(type default)
			)
			(layer "F.Fab")
		)
		(fp_line
			(start -0.2794 0.9906)
			(end 0.2794 0.9906)
			(stroke
				(width 0.1)
				(type default)
			)
			(layer "F.Fab")
		)
		(pad "1" smd rect
			(at 0 0 90)
			(size 0.508 0.508)
			(layers "F.Cu" "F.Mask" "F.Paste")
			(net "P3V3_STBY")
		)
		(pad "2" smd rect
			(at 0 0.889 90)
			(size 0.508 0.508)
			(layers "F.Cu" "F.Mask" "F.Paste")
			(net "SMB_PEHPCPU0_STBY_LVC3_R_SCL")
		)
		(zone
			(layer "F.Cu")
			(hatch none 0.5)
			(connect_pads
				(clearance 0)
			)
			(min_thickness 0.25)
			(keepout
				(tracks allowed)
				(vias not_allowed)
				(pads allowed)
				(copperpour not_allowed)
				(footprints allowed)
			)
			(placement
				(enabled no)
				(sheetname "")
			)
			(fill
				(thermal_gap 0.5)
				(thermal_bridge_width 0.5)
				(island_removal_mode 0)
			)
			(polygon
				(pts
					(xy 419.7985 -112.776) (xy 419.7985 -113.284) (xy 420.1795 -113.284) (xy 420.1795 -112.776)
				)
			)
		)
		(zone
			(layer "F.Cu")
			(hatch none 0.5)
			(connect_pads
				(clearance 0)
			)
			(min_thickness 0.25)
			(keepout
				(tracks not_allowed)
				(vias allowed)
				(pads allowed)
				(copperpour not_allowed)
				(footprints allowed)
			)
			(placement
				(enabled no)
				(sheetname "")
			)
			(fill
				(thermal_gap 0.5)
				(thermal_bridge_width 0.5)
				(island_removal_mode 0)
			)
			(polygon
				(pts
					(xy 420.1795 -112.776) (xy 420.1795 -113.284) (xy 419.7985 -113.284) (xy 419.7985 -112.776)
				)
			)
		)
	)
	(footprint ""
		(layer "F.Cu")
		(at 496.678204 -26.555192)
		(property "Reference" "EU7E1"
			(at 1.8415 2.376932 180)
			(unlocked yes)
			(layer "F.SilkS")
			(effects
				(font
					(size 0.7874 0.5842)
					(thickness 0.1524)
				)
				(justify left)
			)
		)
		(property "Value" ""
			(at 0 0 0)
			(layer "F.Fab")
			(effects
				(font
					(size 1.27 1.27)
				)
			)
		)
		(duplicate_pad_numbers_are_jumpers no)
		(fp_circle
			(center -0.702056 -0.595376)
			(end -0.575056 -0.595376)
			(stroke
				(width 0.254)
				(type default)
			)
			(fill no)
			(layer "F.SilkS")
		)
		(fp_rect
			(start 0.5842 1.549908)
			(end 1.4732 -0.050292)
			(stroke
				(width 0)
				(type default)
			)
			(fill yes)
			(layer "F.Paste")
		)
		(fp_rect
			(start -0.021336 1.799844)
			(end 2.078736 -0.300228)
			(stroke
				(width 0)
				(type default)
			)
			(fill no)
			(layer "F.CrtYd")
		)
		(fp_line
			(start -0.021336 -0.300228)
			(end 2.078736 -0.300228)
			(stroke
				(width 0.1)
				(type default)
			)
			(layer "F.Fab")
		)
		(fp_line
			(start -0.021336 1.799844)
			(end -0.021336 -0.300228)
			(stroke
				(width 0.1)
				(type default)
			)
			(layer "F.Fab")
		)
		(fp_line
			(start 2.078736 -0.300228)
			(end 2.078736 1.799844)
			(stroke
				(width 0.1)
				(type default)
			)
			(layer "F.Fab")
		)
		(fp_line
			(start 2.078736 1.799844)
			(end -0.021336 1.799844)
			(stroke
				(width 0.1)
				(type default)
			)
			(layer "F.Fab")
		)
		(fp_circle
			(center -0.702056 -0.595376)
			(end -0.575056 -0.595376)
			(stroke
				(width 0.254)
				(type default)
			)
			(fill no)
			(layer "F.Fab")
		)
		(pad "1" smd rect
			(at 0 0)
			(size 0.6604 0.3048)
			(layers "F.Cu" "F.Mask" "F.Paste")
			(net "P5V_STBY")
		)
		(pad "2" smd rect
			(at 0 0.499872)
			(size 0.6604 0.3048)
			(layers "F.Cu" "F.Mask" "F.Paste")
			(net "FM_P12V_MAIN_SW_EN")
		)
		(pad "3" smd rect
			(at 0 0.999744)
			(size 0.6604 0.3048)
			(layers "F.Cu" "F.Mask" "F.Paste")
			(net "P5V_STBY")
		)
		(pad "4" smd rect
			(at 0 1.499616)
			(size 0.6604 0.3048)
			(layers "F.Cu" "F.Mask" "F.Paste")
			(net "GND")
		)
		(pad "5" smd rect
			(at 2.0574 1.499616)
			(size 0.6604 0.3048)
			(layers "F.Cu" "F.Mask" "F.Paste")
			(net "P12V_STBY")
		)
		(pad "6" smd rect
			(at 2.0574 0.999744)
			(size 0.6604 0.3048)
			(layers "F.Cu" "F.Mask" "F.Paste")
			(net "P12V")
		)
		(pad "7" smd rect
			(at 2.0574 0.499872)
			(size 0.6604 0.3048)
			(layers "F.Cu" "F.Mask" "F.Paste")
			(net "P12V_SWITCH_G")
		)
		(pad "8" smd rect
			(at 2.0574 0)
			(size 0.6604 0.3048)
			(layers "F.Cu" "F.Mask" "F.Paste")
			(net "TP_SLG55021_P12V_MAIN_8")
		)
		(pad "9" smd rect
			(at 1.0287 0.749808)
			(size 0.889 1.6002)
			(layers "F.Cu" "F.Mask" "F.Paste")
			(net "GND")
		)
	)
	(footprint ""
		(layer "F.Cu")
		(at 184.531 -4.2545 180)
		(property "Reference" "C4G16"
			(at 0 0 180)
			(layer "F.SilkS")
			(hide yes)
			(effects
				(font
					(size 1.27 1.27)
				)
			)
		)
		(property "Value" ""
			(at 0 0 180)
			(layer "F.Fab")
			(effects
				(font
					(size 1.27 1.27)
				)
			)
		)
		(duplicate_pad_numbers_are_jumpers no)
		(fp_rect
			(start 0.3048 -0.1016)
			(end -0.3048 0.9906)
			(stroke
				(width 0)
				(type default)
			)
			(fill no)
			(layer "F.CrtYd")
		)
		(fp_line
			(start 0.3048 0.9906)
			(end 0.3048 -0.1016)
			(stroke
				(width 0.1)
				(type default)
			)
			(layer "F.Fab")
		)
		(fp_line
			(start 0.3048 -0.1016)
			(end -0.3048 -0.1016)
			(stroke
				(width 0.1)
				(type default)
			)
			(layer "F.Fab")
		)
		(fp_line
			(start -0.3048 0.9906)
			(end 0.3048 0.9906)
			(stroke
				(width 0.1)
				(type default)
			)
			(layer "F.Fab")
		)
		(fp_line
			(start -0.3048 -0.1016)
			(end -0.3048 0.9906)
			(stroke
				(width 0.1)
				(type default)
			)
			(layer "F.Fab")
		)
		(pad "1" smd rect
			(at 0 0 180)
			(size 0.508 0.508)
			(layers "F.Cu" "F.Mask" "F.Paste")
			(net "VR_PVTT_ABC_VREF")
		)
		(pad "2" smd rect
			(at 0 0.889 180)
			(size 0.508 0.508)
			(layers "F.Cu" "F.Mask" "F.Paste")
			(net "GND")
		)
		(zone
			(layer "F.Cu")
			(hatch none 0.5)
			(connect_pads
				(clearance 0)
			)
			(min_thickness 0.25)
			(keepout
				(tracks not_allowed)
				(vias allowed)
				(pads allowed)
				(copperpour not_allowed)
				(footprints allowed)
			)
			(placement
				(enabled no)
				(sheetname "")
			)
			(fill
				(thermal_gap 0.5)
				(thermal_bridge_width 0.5)
				(island_removal_mode 0)
			)
			(polygon
				(pts
					(xy 184.277 -4.5085) (xy 184.785 -4.5085) (xy 184.785 -4.8895) (xy 184.277 -4.8895)
				)
			)
		)
		(zone
			(layer "F.Cu")
			(hatch none 0.5)
			(connect_pads
				(clearance 0)
			)
			(min_thickness 0.25)
			(keepout
				(tracks allowed)
				(vias not_allowed)
				(pads allowed)
				(copperpour not_allowed)
				(footprints allowed)
			)
			(placement
				(enabled no)
				(sheetname "")
			)
			(fill
				(thermal_gap 0.5)
				(thermal_bridge_width 0.5)
				(island_removal_mode 0)
			)
			(polygon
				(pts
					(xy 184.277 -4.5085) (xy 184.785 -4.5085) (xy 184.785 -4.8895) (xy 184.277 -4.8895)
				)
			)
		)
	)
	(footprint ""
		(layer "F.Cu")
		(at 381.4572 -140.4366 90)
		(property "Reference" "C3M7"
			(at 0 0 90)
			(layer "F.SilkS")
			(hide yes)
			(effects
				(font
					(size 1.27 1.27)
				)
			)
		)
		(property "Value" ""
			(at 0 0 90)
			(layer "F.Fab")
			(effects
				(font
					(size 1.27 1.27)
				)
			)
		)
		(duplicate_pad_numbers_are_jumpers no)
		(fp_rect
			(start -0.4953 -0.2032)
			(end 0.4953 1.6002)
			(stroke
				(width 0)
				(type default)
			)
			(fill no)
			(layer "F.CrtYd")
		)
		(fp_line
			(start 0.4953 -0.2032)
			(end 0.4953 1.6002)
			(stroke
				(width 0.1)
				(type default)
			)
			(layer "F.Fab")
		)
		(fp_line
			(start -0.4953 -0.2032)
			(end 0.4953 -0.2032)
			(stroke
				(width 0.1)
				(type default)
			)
			(layer "F.Fab")
		)
		(fp_line
			(start 0.4953 1.6002)
			(end -0.4953 1.6002)
			(stroke
				(width 0.1)
				(type default)
			)
			(layer "F.Fab")
		)
		(fp_line
			(start -0.4953 1.6002)
			(end -0.4953 -0.2032)
			(stroke
				(width 0.1)
				(type default)
			)
			(layer "F.Fab")
		)
		(pad "1" smd rect
			(at 0 0 90)
			(size 0.762 0.889)
			(layers "F.Cu" "F.Mask" "F.Paste")
			(net "PVNN_PCH_STBY")
		)
		(pad "2" smd rect
			(at 0 1.397 90)
			(size 0.762 0.889)
			(layers "F.Cu" "F.Mask" "F.Paste")
			(net "GND")
		)
		(zone
			(layer "F.Cu")
			(hatch none 0.5)
			(connect_pads
				(clearance 0)
			)
			(min_thickness 0.25)
			(keepout
				(tracks not_allowed)
				(vias allowed)
				(pads allowed)
				(copperpour not_allowed)
				(footprints allowed)
			)
			(placement
				(enabled no)
				(sheetname "")
			)
			(fill
				(thermal_gap 0.5)
				(thermal_bridge_width 0.5)
				(island_removal_mode 0)
			)
			(polygon
				(pts
					(xy 381.9017 -140.0556) (xy 382.4097 -140.0556) (xy 382.4097 -140.8176) (xy 381.9017 -140.8176)
				)
			)
		)
	)
	(footprint ""
		(layer "F.Cu")
		(at 175.2346 -93.3958 180)
		(property "Reference" "R4C9"
			(at 0 0 180)
			(layer "F.SilkS")
			(hide yes)
			(effects
				(font
					(size 1.27 1.27)
				)
			)
		)
		(property "Value" ""
			(at 0 0 180)
			(layer "F.Fab")
			(effects
				(font
					(size 1.27 1.27)
				)
			)
		)
		(duplicate_pad_numbers_are_jumpers no)
		(fp_poly
			(pts
				(xy -0.2794 -0.1016) (xy 0.2794 -0.1016) (xy 0.2794 0.9906) (xy -0.2794 0.9906)
			)
			(stroke
				(width 0)
				(type default)
			)
			(fill no)
			(layer "F.CrtYd")
		)
		(fp_line
			(start 0.2794 0.9906)
			(end 0.2794 -0.1016)
			(stroke
				(width 0.1)
				(type default)
			)
			(layer "F.Fab")
		)
		(fp_line
			(start 0.2794 -0.1016)
			(end -0.2794 -0.1016)
			(stroke
				(width 0.1)
				(type default)
			)
			(layer "F.Fab")
		)
		(fp_line
			(start -0.2794 0.9906)
			(end 0.2794 0.9906)
			(stroke
				(width 0.1)
				(type default)
			)
			(layer "F.Fab")
		)
		(fp_line
			(start -0.2794 -0.1016)
			(end -0.2794 0.9906)
			(stroke
				(width 0.1)
				(type default)
			)
			(layer "F.Fab")
		)
		(pad "1" smd rect
			(at 0 0 180)
			(size 0.508 0.508)
			(layers "F.Cu" "F.Mask" "F.Paste")
			(net "GND")
		)
		(pad "2" smd rect
			(at 0 0.889 180)
			(size 0.508 0.508)
			(layers "F.Cu" "F.Mask" "F.Paste")
			(net "PD_GTL2014_2_VREF")
		)
		(zone
			(layer "F.Cu")
			(hatch none 0.5)
			(connect_pads
				(clearance 0)
			)
			(min_thickness 0.25)
			(keepout
				(tracks not_allowed)
				(vias allowed)
				(pads allowed)
				(copperpour not_allowed)
				(footprints allowed)
			)
			(placement
				(enabled no)
				(sheetname "")
			)
			(fill
				(thermal_gap 0.5)
				(thermal_bridge_width 0.5)
				(island_removal_mode 0)
			)
			(polygon
				(pts
					(xy 175.4886 -94.0308) (xy 174.9806 -94.0308) (xy 174.9806 -93.6498) (xy 175.4886 -93.6498)
				)
			)
		)
		(zone
			(layer "F.Cu")
			(hatch none 0.5)
			(connect_pads
				(clearance 0)
			)
			(min_thickness 0.25)
			(keepout
				(tracks allowed)
				(vias not_allowed)
				(pads allowed)
				(copperpour not_allowed)
				(footprints allowed)
			)
			(placement
				(enabled no)
				(sheetname "")
			)
			(fill
				(thermal_gap 0.5)
				(thermal_bridge_width 0.5)
				(island_removal_mode 0)
			)
			(polygon
				(pts
					(xy 175.4886 -93.6498) (xy 174.9806 -93.6498) (xy 174.9806 -94.0308) (xy 175.4886 -94.0308)
				)
			)
		)
	)
	(footprint ""
		(layer "F.Cu")
		(at 318.543432 -149.86 -90)
		(property "Reference" "C6A2"
			(at 0 0 270)
			(layer "F.SilkS")
			(hide yes)
			(effects
				(font
					(size 1.27 1.27)
				)
			)
		)
		(property "Value" ""
			(at 0 0 270)
			(layer "F.Fab")
			(effects
				(font
					(size 1.27 1.27)
				)
			)
		)
		(duplicate_pad_numbers_are_jumpers no)
		(fp_poly
			(pts
				(xy -0.4953 -0.2032) (xy 0.4953 -0.2032) (xy 0.4953 1.6002) (xy -0.4953 1.6002)
			)
			(stroke
				(width 0)
				(type default)
			)
			(fill no)
			(layer "F.CrtYd")
		)
		(fp_line
			(start -0.4953 1.6002)
			(end -0.4953 -0.2032)
			(stroke
				(width 0.1)
				(type default)
			)
			(layer "F.Fab")
		)
		(fp_line
			(start 0.4953 1.6002)
			(end -0.4953 1.6002)
			(stroke
				(width 0.1)
				(type default)
			)
			(layer "F.Fab")
		)
		(fp_line
			(start -0.4953 -0.2032)
			(end 0.4953 -0.2032)
			(stroke
				(width 0.1)
				(type default)
			)
			(layer "F.Fab")
		)
		(fp_line
			(start 0.4953 -0.2032)
			(end 0.4953 1.6002)
			(stroke
				(width 0.1)
				(type default)
			)
			(layer "F.Fab")
		)
		(pad "1" smd rect
			(at 0 0 270)
			(size 0.762 0.889)
			(layers "F.Cu" "F.Mask" "F.Paste")
			(net "PVPP_DEF")
		)
		(pad "2" smd rect
			(at 0 1.397 270)
			(size 0.762 0.889)
			(layers "F.Cu" "F.Mask" "F.Paste")
			(net "GND")
		)
		(zone
			(layer "F.Cu")
			(hatch none 0.5)
			(connect_pads
				(clearance 0)
			)
			(min_thickness 0.25)
			(keepout
				(tracks not_allowed)
				(vias allowed)
				(pads allowed)
				(copperpour not_allowed)
				(footprints allowed)
			)
			(placement
				(enabled no)
				(sheetname "")
			)
			(fill
				(thermal_gap 0.5)
				(thermal_bridge_width 0.5)
				(island_removal_mode 0)
			)
			(polygon
				(pts
					(xy 318.098932 -150.241) (xy 318.098932 -149.479) (xy 317.590932 -149.479) (xy 317.590932 -150.241)
				)
			)
		)
	)
	(footprint ""
		(layer "F.Cu")
		(at 348.384114 -23.486618)
		(property "Reference" "R7F16"
			(at 0 0 0)
			(layer "F.SilkS")
			(hide yes)
			(effects
				(font
					(size 1.27 1.27)
				)
			)
		)
		(property "Value" ""
			(at 0 0 0)
			(layer "F.Fab")
			(effects
				(font
					(size 1.27 1.27)
				)
			)
		)
		(duplicate_pad_numbers_are_jumpers no)
		(fp_poly
			(pts
				(xy -0.2794 -0.1016) (xy 0.2794 -0.1016) (xy 0.2794 0.9906) (xy -0.2794 0.9906)
			)
			(stroke
				(width 0)
				(type default)
			)
			(fill no)
			(layer "F.CrtYd")
		)
		(fp_line
			(start -0.2794 -0.1016)
			(end -0.2794 0.9906)
			(stroke
				(width 0.1)
				(type default)
			)
			(layer "F.Fab")
		)
		(fp_line
			(start -0.2794 0.9906)
			(end 0.2794 0.9906)
			(stroke
				(width 0.1)
				(type default)
			)
			(layer "F.Fab")
		)
		(fp_line
			(start 0.2794 -0.1016)
			(end -0.2794 -0.1016)
			(stroke
				(width 0.1)
				(type default)
			)
			(layer "F.Fab")
		)
		(fp_line
			(start 0.2794 0.9906)
			(end 0.2794 -0.1016)
			(stroke
				(width 0.1)
				(type default)
			)
			(layer "F.Fab")
		)
		(pad "1" smd rect
			(at 0 0)
			(size 0.508 0.508)
			(layers "F.Cu" "F.Mask" "F.Paste")
			(net "PWRGD_PVPP_ABC_R")
		)
		(pad "2" smd rect
			(at 0 0.889)
			(size 0.508 0.508)
			(layers "F.Cu" "F.Mask" "F.Paste")
			(net "PWRGD_PVPP_ABC")
		)
		(zone
			(layer "F.Cu")
			(hatch none 0.5)
			(connect_pads
				(clearance 0)
			)
			(min_thickness 0.25)
			(keepout
				(tracks allowed)
				(vias not_allowed)
				(pads allowed)
				(copperpour not_allowed)
				(footprints allowed)
			)
			(placement
				(enabled no)
				(sheetname "")
			)
			(fill
				(thermal_gap 0.5)
				(thermal_bridge_width 0.5)
				(island_removal_mode 0)
			)
			(polygon
				(pts
					(xy 348.130114 -23.232618) (xy 348.638114 -23.232618) (xy 348.638114 -22.851618) (xy 348.130114 -22.851618)
				)
			)
		)
		(zone
			(layer "F.Cu")
			(hatch none 0.5)
			(connect_pads
				(clearance 0)
			)
			(min_thickness 0.25)
			(keepout
				(tracks not_allowed)
				(vias allowed)
				(pads allowed)
				(copperpour not_allowed)
				(footprints allowed)
			)
			(placement
				(enabled no)
				(sheetname "")
			)
			(fill
				(thermal_gap 0.5)
				(thermal_bridge_width 0.5)
				(island_removal_mode 0)
			)
			(polygon
				(pts
					(xy 348.130114 -22.851618) (xy 348.638114 -22.851618) (xy 348.638114 -23.232618) (xy 348.130114 -23.232618)
				)
			)
		)
	)
)
